# S9S_MB_2U (Grand Teton) — schematic netlist excerpt (pin names and nets, part order shuffled) for the footprints in the layout excerpt that follows; sources: Cadence DE-HDL packaged netlist, KiCad conversion of 03242023_DA0F0TMBIJ0_F0T_Motherboard_J_brd_V01_OCP.brd

R650  Q_RES  1K 1% CHIP  pkg 0402LF  page 127 : A = P3V3_AUX ; B = PU_PIROM_CPU0_SM_WP
C2194  Q_CAP  0.1UF 25V 10% X7R  pkg 0402  page 250 : A = P12V_E1S_0_ISENSE_TIC ; B = GND

(kicad_pcb
	(version 20260206)
	(generator "pcbnew")
	(generator_version "10.0")
	(general
		(thickness 1.6)
		(legacy_teardrops no)
	)
	(paper "A4")
	(title_block
		(title "03242023_DA0F0TMBIJ0_F0T_Motherboard_J_brd_V01_OCP.brd")
		(comment 1 "Grand Teton / footprints 1057-1058 of 6105")
	)
	(layers
		(0 "F.Cu" signal "TOP")
		(4 "In1.Cu" signal "GND")
		(6 "In2.Cu" signal "IN1")
		(8 "In3.Cu" signal "GND1")
		(10 "In4.Cu" signal "IN2")
		(12 "In5.Cu" signal "GND2")
		(14 "In6.Cu" signal "IN3")
		(16 "In7.Cu" signal "GND3")
		(18 "In8.Cu" signal "VCC")
		(20 "In9.Cu" signal "VCC1")
		(22 "In10.Cu" signal "GND4")
		(24 "In11.Cu" signal "IN4")
		(26 "In12.Cu" signal "GND5")
		(28 "In13.Cu" signal "IN5")
		(30 "In14.Cu" signal "GND6")
		(32 "In15.Cu" signal "IN6")
		(34 "In16.Cu" signal "GND7")
		(2 "B.Cu" signal "BOTTOM")
		(9 "F.Adhes" user "F.Adhesive")
		(11 "B.Adhes" user "B.Adhesive")
		(13 "F.Paste" user "Package Geometry/Pastemask Top")
		(15 "B.Paste" user "Package Geometry/Pastemask Bottom")
		(5 "F.SilkS" user "Ref Des/Silkscreen Top")
		(7 "B.SilkS" user "Ref Des/Silkscreen Bottom")
		(1 "F.Mask" user "Board Geometry/Soldermask Top")
		(3 "B.Mask" user "Board Geometry/Soldermask Bottom")
		(17 "Dwgs.User" user "User.Drawings")
		(19 "Cmts.User" user "User.Comments")
		(21 "Eco1.User" user "User.Eco1")
		(23 "Eco2.User" user "User.Eco2")
		(25 "Edge.Cuts" user "Board Geometry/Outline")
		(27 "Margin" user)
		(31 "F.CrtYd" user "Package Geometry/Place Bound Top")
		(29 "B.CrtYd" user "Package Geometry/Place Bound Bottom")
		(35 "F.Fab" user "Ref Des/Assembly Top")
		(33 "B.Fab" user "Ref Des/Assembly Bottom")
	)
	(footprint ""
		(layer "F.Cu")
		(at 36.930584 -105.425748)
		(property "Reference" "C2194"
			(at 0 0 0)
			(layer "F.SilkS")
			(hide yes)
			(effects
				(font
					(size 1.27 1.27)
				)
			)
		)
		(property "Value" ""
			(at 0 0 0)
			(layer "F.Fab")
			(effects
				(font
					(size 1.27 1.27)
				)
			)
		)
		(duplicate_pad_numbers_are_jumpers no)
		(fp_line
			(start -0.7874 -0.4064)
			(end 0.7874 -0.4064)
			(stroke
				(width 0.1524)
				(type default)
			)
			(layer "F.SilkS")
		)
		(fp_line
			(start -0.7874 0.4064)
			(end -0.7874 -0.4064)
			(stroke
				(width 0.1524)
				(type default)
			)
			(layer "F.SilkS")
		)
		(fp_line
			(start 0.7874 -0.4064)
			(end 0.7874 0.4064)
			(stroke
				(width 0.1524)
				(type default)
			)
			(layer "F.SilkS")
		)
		(fp_line
			(start 0.7874 0.4064)
			(end -0.7874 0.4064)
			(stroke
				(width 0.1524)
				(type default)
			)
			(layer "F.SilkS")
		)
		(fp_line
			(start -0.67945 -0.305054)
			(end -0.12065 -0.305054)
			(stroke
				(width 0.1)
				(type default)
			)
			(layer "F.Fab")
		)
		(fp_line
			(start -0.67945 0.3048)
			(end -0.67945 -0.305054)
			(stroke
				(width 0.1)
				(type default)
			)
			(layer "F.Fab")
		)
		(fp_line
			(start -0.12065 -0.305054)
			(end -0.12065 -0.2794)
			(stroke
				(width 0.1)
				(type default)
			)
			(layer "F.Fab")
		)
		(fp_line
			(start -0.12065 -0.2794)
			(end 0.12065 -0.2794)
			(stroke
				(width 0.1)
				(type default)
			)
			(layer "F.Fab")
		)
		(fp_line
			(start -0.12065 0.2794)
			(end -0.12065 0.3048)
			(stroke
				(width 0.1)
				(type default)
			)
			(layer "F.Fab")
		)
		(fp_line
			(start -0.12065 0.3048)
			(end -0.67945 0.3048)
			(stroke
				(width 0.1)
				(type default)
			)
			(layer "F.Fab")
		)
		(fp_line
			(start 0.120396 0.2794)
			(end -0.12065 0.2794)
			(stroke
				(width 0.1)
				(type default)
			)
			(layer "F.Fab")
		)
		(fp_line
			(start 0.120396 0.3048)
			(end 0.120396 0.2794)
			(stroke
				(width 0.1)
				(type default)
			)
			(layer "F.Fab")
		)
		(fp_line
			(start 0.12065 -0.3048)
			(end 0.67945 -0.3048)
			(stroke
				(width 0.1)
				(type default)
			)
			(layer "F.Fab")
		)
		(fp_line
			(start 0.12065 -0.2794)
			(end 0.12065 -0.3048)
			(stroke
				(width 0.1)
				(type default)
			)
			(layer "F.Fab")
		)
		(fp_line
			(start 0.67945 -0.3048)
			(end 0.67945 0.3048)
			(stroke
				(width 0.1)
				(type default)
			)
			(layer "F.Fab")
		)
		(fp_line
			(start 0.67945 0.3048)
			(end 0.120396 0.3048)
			(stroke
				(width 0.1)
				(type default)
			)
			(layer "F.Fab")
		)
		(pad "1" smd circle
			(at -0.40005 0)
			(size 0 0)
			(layers "F.Cu" "F.Mask" "F.Paste")
			(net "P12V_E1S_0_ISENSE_TIC")
		)
		(pad "2" smd circle
			(at 0.40005 0)
			(size 0 0)
			(layers "F.Cu" "F.Mask" "F.Paste")
			(net "GND")
		)
	)
	(footprint ""
		(layer "F.Cu")
		(at 406.124664 -366.437926 180)
		(property "Reference" "R650"
			(at 0 0 180)
			(layer "F.SilkS")
			(hide yes)
			(effects
				(font
					(size 1.27 1.27)
				)
			)
		)
		(property "Value" ""
			(at 0 0 180)
			(layer "F.Fab")
			(effects
				(font
					(size 1.27 1.27)
				)
			)
		)
		(duplicate_pad_numbers_are_jumpers no)
		(fp_line
			(start 0.7874 0.4064)
			(end -0.7874 0.4064)
			(stroke
				(width 0.1524)
				(type default)
			)
			(layer "F.SilkS")
		)
		(fp_line
			(start 0.7874 -0.4064)
			(end 0.7874 0.4064)
			(stroke
				(width 0.1524)
				(type default)
			)
			(layer "F.SilkS")
		)
		(fp_line
			(start -0.7874 0.4064)
			(end -0.7874 -0.4064)
			(stroke
				(width 0.1524)
				(type default)
			)
			(layer "F.SilkS")
		)
		(fp_line
			(start -0.7874 -0.4064)
			(end 0.7874 -0.4064)
			(stroke
				(width 0.1524)
				(type default)
			)
			(layer "F.SilkS")
		)
		(fp_line
			(start 0.67945 0.3048)
			(end 0.120396 0.3048)
			(stroke
				(width 0.1)
				(type default)
			)
			(layer "F.Fab")
		)
		(fp_line
			(start 0.67945 -0.3048)
			(end 0.67945 0.3048)
			(stroke
				(width 0.1)
				(type default)
			)
			(layer "F.Fab")
		)
		(fp_line
			(start 0.12065 -0.2794)
			(end 0.12065 -0.3048)
			(stroke
				(width 0.1)
				(type default)
			)
			(layer "F.Fab")
		)
		(fp_line
			(start 0.12065 -0.3048)
			(end 0.67945 -0.3048)
			(stroke
				(width 0.1)
				(type default)
			)
			(layer "F.Fab")
		)
		(fp_line
			(start 0.120396 0.3048)
			(end 0.120396 0.2794)
			(stroke
				(width 0.1)
				(type default)
			)
			(layer "F.Fab")
		)
		(fp_line
			(start 0.120396 0.2794)
			(end -0.12065 0.2794)
			(stroke
				(width 0.1)
				(type default)
			)
			(layer "F.Fab")
		)
		(fp_line
			(start -0.12065 0.3048)
			(end -0.67945 0.3048)
			(stroke
				(width 0.1)
				(type default)
			)
			(layer "F.Fab")
		)
		(fp_line
			(start -0.12065 0.2794)
			(end -0.12065 0.3048)
			(stroke
				(width 0.1)
				(type default)
			)
			(layer "F.Fab")
		)
		(fp_line
			(start -0.12065 -0.2794)
			(end 0.12065 -0.2794)
			(stroke
				(width 0.1)
				(type default)
			)
			(layer "F.Fab")
		)
		(fp_line
			(start -0.12065 -0.305054)
			(end -0.12065 -0.2794)
			(stroke
				(width 0.1)
				(type default)
			)
			(layer "F.Fab")
		)
		(fp_line
			(start -0.67945 0.3048)
			(end -0.67945 -0.305054)
			(stroke
				(width 0.1)
				(type default)
			)
			(layer "F.Fab")
		)
		(fp_line
			(start -0.67945 -0.305054)
			(end -0.12065 -0.305054)
			(stroke
				(width 0.1)
				(type default)
			)
			(layer "F.Fab")
		)
		(pad "1" smd circle
			(at -0.40005 0 180)
			(size 0 0)
			(layers "F.Cu" "F.Mask" "F.Paste")
			(net "P3V3_AUX")
		)
		(pad "2" smd circle
			(at 0.40005 0 180)
			(size 0 0)
			(layers "F.Cu" "F.Mask" "F.Paste")
			(net "PU_PIROM_CPU0_SM_WP")
		)
	)
)
